# S9S_MB_2U (Grand Teton) — schematic netlist excerpt (pin names and nets, part order shuffled) for the footprints in the layout excerpt that follows; sources: Cadence DE-HDL packaged netlist, KiCad conversion of 03242023_DA0F0TMBIJ0_F0T_Motherboard_J_brd_V01_OCP.brd

R4477  Q_RES  33.2 1% CHIP  pkg 0402LF  page 211 : A = FM_9ZXL045_0_OE_N ; B = CLK_SWB_BUF2_OE_N
R3200  Q_RES  22 1% CHIP  pkg 0402LF  page 207 : A = CLK_100M_OCP_V3_2_D_R_DP ; B = CLK_100M_OCP_V3_2_D_DP
H99  HOLE  EMPTY  pkg TH  page 311 : \1\ = GND

(kicad_pcb
	(version 20260206)
	(generator "pcbnew")
	(generator_version "10.0")
	(general
		(thickness 1.6)
		(legacy_teardrops no)
	)
	(paper "A4")
	(title_block
		(title "03242023_DA0F0TMBIJ0_F0T_Motherboard_J_brd_V01_OCP.brd")
		(comment 1 "Grand Teton / footprints 93-95 of 6105")
	)
	(layers
		(0 "F.Cu" signal "TOP")
		(4 "In1.Cu" signal "GND")
		(6 "In2.Cu" signal "IN1")
		(8 "In3.Cu" signal "GND1")
		(10 "In4.Cu" signal "IN2")
		(12 "In5.Cu" signal "GND2")
		(14 "In6.Cu" signal "IN3")
		(16 "In7.Cu" signal "GND3")
		(18 "In8.Cu" signal "VCC")
		(20 "In9.Cu" signal "VCC1")
		(22 "In10.Cu" signal "GND4")
		(24 "In11.Cu" signal "IN4")
		(26 "In12.Cu" signal "GND5")
		(28 "In13.Cu" signal "IN5")
		(30 "In14.Cu" signal "GND6")
		(32 "In15.Cu" signal "IN6")
		(34 "In16.Cu" signal "GND7")
		(2 "B.Cu" signal "BOTTOM")
		(9 "F.Adhes" user "F.Adhesive")
		(11 "B.Adhes" user "B.Adhesive")
		(13 "F.Paste" user "Package Geometry/Pastemask Top")
		(15 "B.Paste" user "Package Geometry/Pastemask Bottom")
		(5 "F.SilkS" user "Ref Des/Silkscreen Top")
		(7 "B.SilkS" user "Ref Des/Silkscreen Bottom")
		(1 "F.Mask" user "Board Geometry/Soldermask Top")
		(3 "B.Mask" user "Board Geometry/Soldermask Bottom")
		(17 "Dwgs.User" user "User.Drawings")
		(19 "Cmts.User" user "User.Comments")
		(21 "Eco1.User" user "User.Eco1")
		(23 "Eco2.User" user "User.Eco2")
		(25 "Edge.Cuts" user "Board Geometry/Outline")
		(27 "Margin" user)
		(31 "F.CrtYd" user "Package Geometry/Place Bound Top")
		(29 "B.CrtYd" user "Package Geometry/Place Bound Bottom")
		(35 "F.Fab" user "Ref Des/Assembly Top")
		(33 "B.Fab" user "Ref Des/Assembly Bottom")
	)
	(footprint ""
		(layer "F.Cu")
		(at 243.03228 -121.986548)
		(property "Reference" "R3200"
			(at 0 0 0)
			(layer "F.SilkS")
			(hide yes)
			(effects
				(font
					(size 1.27 1.27)
				)
			)
		)
		(property "Value" ""
			(at 0 0 0)
			(layer "F.Fab")
			(effects
				(font
					(size 1.27 1.27)
				)
			)
		)
		(duplicate_pad_numbers_are_jumpers no)
		(fp_line
			(start -0.7874 0.4064)
			(end -0.7874 -0.057912)
			(stroke
				(width 0.1524)
				(type default)
			)
			(layer "F.SilkS")
		)
		(fp_line
			(start -0.45212 -0.4064)
			(end 0.47498 -0.4064)
			(stroke
				(width 0.1524)
				(type default)
			)
			(layer "F.SilkS")
		)
		(fp_line
			(start 0.7874 -0.113792)
			(end 0.7874 0.4064)
			(stroke
				(width 0.1524)
				(type default)
			)
			(layer "F.SilkS")
		)
		(fp_line
			(start 0.7874 0.4064)
			(end -0.7874 0.4064)
			(stroke
				(width 0.1524)
				(type default)
			)
			(layer "F.SilkS")
		)
		(fp_line
			(start -0.67945 -0.305054)
			(end -0.12065 -0.305054)
			(stroke
				(width 0.1)
				(type default)
			)
			(layer "F.Fab")
		)
		(fp_line
			(start -0.67945 0.3048)
			(end -0.67945 -0.305054)
			(stroke
				(width 0.1)
				(type default)
			)
			(layer "F.Fab")
		)
		(fp_line
			(start -0.12065 -0.305054)
			(end -0.12065 -0.2794)
			(stroke
				(width 0.1)
				(type default)
			)
			(layer "F.Fab")
		)
		(fp_line
			(start -0.12065 -0.2794)
			(end 0.12065 -0.2794)
			(stroke
				(width 0.1)
				(type default)
			)
			(layer "F.Fab")
		)
		(fp_line
			(start -0.12065 0.2794)
			(end -0.12065 0.3048)
			(stroke
				(width 0.1)
				(type default)
			)
			(layer "F.Fab")
		)
		(fp_line
			(start -0.12065 0.3048)
			(end -0.67945 0.3048)
			(stroke
				(width 0.1)
				(type default)
			)
			(layer "F.Fab")
		)
		(fp_line
			(start 0.120396 0.2794)
			(end -0.12065 0.2794)
			(stroke
				(width 0.1)
				(type default)
			)
			(layer "F.Fab")
		)
		(fp_line
			(start 0.120396 0.3048)
			(end 0.120396 0.2794)
			(stroke
				(width 0.1)
				(type default)
			)
			(layer "F.Fab")
		)
		(fp_line
			(start 0.12065 -0.3048)
			(end 0.67945 -0.3048)
			(stroke
				(width 0.1)
				(type default)
			)
			(layer "F.Fab")
		)
		(fp_line
			(start 0.12065 -0.2794)
			(end 0.12065 -0.3048)
			(stroke
				(width 0.1)
				(type default)
			)
			(layer "F.Fab")
		)
		(fp_line
			(start 0.67945 -0.3048)
			(end 0.67945 0.3048)
			(stroke
				(width 0.1)
				(type default)
			)
			(layer "F.Fab")
		)
		(fp_line
			(start 0.67945 0.3048)
			(end 0.120396 0.3048)
			(stroke
				(width 0.1)
				(type default)
			)
			(layer "F.Fab")
		)
		(pad "1" smd circle
			(at -0.40005 0)
			(size 0 0)
			(layers "F.Cu" "F.Mask" "F.Paste")
			(net "CLK_100M_OCP_V3_2_D_R_DP")
		)
		(pad "2" smd circle
			(at 0.40005 0)
			(size 0 0)
			(layers "F.Cu" "F.Mask" "F.Paste")
			(net "CLK_100M_OCP_V3_2_D_DP")
		)
	)
	(footprint ""
		(layer "F.Cu")
		(at 236.649768 -272.499836)
		(property "Reference" "H99"
			(at -4.60756 -4.956048 0)
			(unlocked yes)
			(layer "F.SilkS")
			(effects
				(font
					(size 0.7874 0.5842)
					(thickness 0.1524)
				)
				(justify left)
			)
		)
		(property "Value" ""
			(at 0 0 0)
			(layer "F.Fab")
			(effects
				(font
					(size 1.27 1.27)
				)
			)
		)
		(duplicate_pad_numbers_are_jumpers no)
		(pad "1" thru_hole circle
			(at 0 0)
			(size 10.0076 10.0076)
			(drill 5.6134)
			(layers "*.Cu" "*.Mask")
			(remove_unused_layers no)
			(net "GND")
			(clearance -1.9431)
		)
	)
	(footprint ""
		(layer "F.Cu")
		(at 106.86542 -418.392864 180)
		(property "Reference" "R4477"
			(at 0 0 180)
			(layer "F.SilkS")
			(hide yes)
			(effects
				(font
					(size 1.27 1.27)
				)
			)
		)
		(property "Value" ""
			(at 0 0 180)
			(layer "F.Fab")
			(effects
				(font
					(size 1.27 1.27)
				)
			)
		)
		(duplicate_pad_numbers_are_jumpers no)
		(fp_line
			(start 0.7874 0.4064)
			(end -0.7874 0.4064)
			(stroke
				(width 0.1524)
				(type default)
			)
			(layer "F.SilkS")
		)
		(fp_line
			(start 0.7874 -0.4064)
			(end 0.7874 0.4064)
			(stroke
				(width 0.1524)
				(type default)
			)
			(layer "F.SilkS")
		)
		(fp_line
			(start -0.7874 0.4064)
			(end -0.7874 -0.4064)
			(stroke
				(width 0.1524)
				(type default)
			)
			(layer "F.SilkS")
		)
		(fp_line
			(start -0.7874 -0.4064)
			(end 0.7874 -0.4064)
			(stroke
				(width 0.1524)
				(type default)
			)
			(layer "F.SilkS")
		)
		(fp_line
			(start 0.67945 0.3048)
			(end 0.120396 0.3048)
			(stroke
				(width 0.1)
				(type default)
			)
			(layer "F.Fab")
		)
		(fp_line
			(start 0.67945 -0.3048)
			(end 0.67945 0.3048)
			(stroke
				(width 0.1)
				(type default)
			)
			(layer "F.Fab")
		)
		(fp_line
			(start 0.12065 -0.2794)
			(end 0.12065 -0.3048)
			(stroke
				(width 0.1)
				(type default)
			)
			(layer "F.Fab")
		)
		(fp_line
			(start 0.12065 -0.3048)
			(end 0.67945 -0.3048)
			(stroke
				(width 0.1)
				(type default)
			)
			(layer "F.Fab")
		)
		(fp_line
			(start 0.120396 0.3048)
			(end 0.120396 0.2794)
			(stroke
				(width 0.1)
				(type default)
			)
			(layer "F.Fab")
		)
		(fp_line
			(start 0.120396 0.2794)
			(end -0.12065 0.2794)
			(stroke
				(width 0.1)
				(type default)
			)
			(layer "F.Fab")
		)
		(fp_line
			(start -0.12065 0.3048)
			(end -0.67945 0.3048)
			(stroke
				(width 0.1)
				(type default)
			)
			(layer "F.Fab")
		)
		(fp_line
			(start -0.12065 0.2794)
			(end -0.12065 0.3048)
			(stroke
				(width 0.1)
				(type default)
			)
			(layer "F.Fab")
		)
		(fp_line
			(start -0.12065 -0.2794)
			(end 0.12065 -0.2794)
			(stroke
				(width 0.1)
				(type default)
			)
			(layer "F.Fab")
		)
		(fp_line
			(start -0.12065 -0.305054)
			(end -0.12065 -0.2794)
			(stroke
				(width 0.1)
				(type default)
			)
			(layer "F.Fab")
		)
		(fp_line
			(start -0.67945 0.3048)
			(end -0.67945 -0.305054)
			(stroke
				(width 0.1)
				(type default)
			)
			(layer "F.Fab")
		)
		(fp_line
			(start -0.67945 -0.305054)
			(end -0.12065 -0.305054)
			(stroke
				(width 0.1)
				(type default)
			)
			(layer "F.Fab")
		)
		(pad "1" smd circle
			(at -0.40005 0 180)
			(size 0 0)
			(layers "F.Cu" "F.Mask" "F.Paste")
			(net "FM_9ZXL045_0_OE_N")
		)
		(pad "2" smd circle
			(at 0.40005 0 180)
			(size 0 0)
			(layers "F.Cu" "F.Mask" "F.Paste")
			(net "CLK_SWB_BUF2_OE_N")
		)
	)
)
